G04 ================== begin FILE IDENTIFICATION RECORD ==================*
G04 Layout Name:  D:/<user>/Wistron_project/16369-sd/gbr/16369-sd.brd*
G04 Film Name:    TMASK*
G04 File Format:  Gerber RS274X*
G04 File Origin:  Cadence Allegro 16.5-S056*
G04 Origin Date:  Wed Mar 29 13:12:47 2017*
G04 *
G04 Layer:  VIA CLASS/SOLDERMASK_TOP*
G04 Layer:  PIN/SOLDERMASK_TOP*
G04 Layer:  PACKAGE GEOMETRY/SOLDERMASK_TOP*
G04 Layer:  DRAWING FORMAT/LAYER_PCB_STORY*
G04 Layer:  DRAWING FORMAT/LAYER_SOLDER_T*
G04 Layer:  BOARD GEOMETRY/SOLDERMASK_TOP*
G04 *
G04 Offset:    (0.00 0.00)*
G04 Mirror:    No*
G04 Mode:      Positive*
G04 Rotation:  0*
G04 FullContactRelief:  No*
G04 UndefLineWidth:     6.00*
G04 ================== end FILE IDENTIFICATION RECORD ====================*
%FSLAX35Y35*MOIN*%
%IR0*IPPOS*OFA0.00000B0.00000*MIA0B0*SFA1.00000B1.00000*%
%AMMACRO62*
4,1,40,.017,-.013,
.017,.013,
.016939,.013695,
.016759,.014368,
.016464,.015,
.016064,.015571,
.015571,.016064,
.015,.016464,
.014368,.016759,
.013695,.016939,
.013,.017,
-.013,.017,
-.013695,.016939,
-.014368,.016759,
-.015,.016464,
-.015571,.016064,
-.016064,.015571,
-.016464,.015,
-.016759,.014368,
-.016939,.013695,
-.017,.013,
-.017,-.013,
-.016939,-.013695,
-.016759,-.014368,
-.016464,-.015,
-.016064,-.015571,
-.015571,-.016064,
-.015,-.016464,
-.014368,-.016759,
-.013695,-.016939,
-.013,-.017,
.013,-.017,
.013695,-.016939,
.014368,-.016759,
.015,-.016464,
.015571,-.016064,
.016064,-.015571,
.016464,-.015,
.016759,-.014368,
.016939,-.013695,
.017,-.013,
0.0*
%
%ADD62MACRO62*%
%AMMACRO42*
4,1,40,.013,.017,
-.013,.017,
-.013695,.016939,
-.014368,.016759,
-.015,.016464,
-.015571,.016064,
-.016064,.015571,
-.016464,.015,
-.016759,.014368,
-.016939,.013695,
-.017,.013,
-.017,-.013,
-.016939,-.013695,
-.016759,-.014368,
-.016464,-.015,
-.016064,-.015571,
-.015571,-.016064,
-.015,-.016464,
-.014368,-.016759,
-.013695,-.016939,
-.013,-.017,
.013,-.017,
.013695,-.016939,
.014368,-.016759,
.015,-.016464,
.015571,-.016064,
.016064,-.015571,
.016464,-.015,
.016759,-.014368,
.016939,-.013695,
.017,-.013,
.017,.013,
.016939,.013695,
.016759,.014368,
.016464,.015,
.016064,.015571,
.015571,.016064,
.015,.016464,
.014368,.016759,
.013695,.016939,
.013,.017,
0.0*
%
%ADD42MACRO42*%
%AMMACRO63*
4,1,40,.008,.009,
.008695,.008939,
.009368,.008759,
.01,.008464,
.010571,.008064,
.011064,.007571,
.011464,.007,
.011759,.006368,
.011939,.005695,
.012,.005,
.012,-.005,
.011939,-.005695,
.011759,-.006368,
.011464,-.007,
.011064,-.007571,
.010571,-.008064,
.01,-.008464,
.009368,-.008759,
.008695,-.008939,
.008,-.009,
-.008,-.009,
-.008695,-.008939,
-.009368,-.008759,
-.01,-.008464,
-.010571,-.008064,
-.011064,-.007571,
-.011464,-.007,
-.011759,-.006368,
-.011939,-.005695,
-.012,-.005,
-.012,.005,
-.011939,.005695,
-.011759,.006368,
-.011464,.007,
-.011064,.007571,
-.010571,.008064,
-.01,.008464,
-.009368,.008759,
-.008695,.008939,
-.008,.009,
.008,.009,
0.0*
%
%ADD63MACRO63*%
%ADD53C,.02*%
%ADD43C,.032*%
%ADD44C,.042*%
%ADD14C,.052*%
%ADD26C,.026*%
%ADD11C,.08*%
%ADD46C,.028*%
%ADD40C,.046*%
%ADD10C,.086*%
%AMMACRO32*
4,1,40,.011,-.007,
.011,.007,
.010939,.007695,
.010759,.008368,
.010464,.009,
.010064,.009571,
.009571,.010064,
.009,.010464,
.008368,.010759,
.007695,.010939,
.007,.011,
-.007,.011,
-.007695,.010939,
-.008368,.010759,
-.009,.010464,
-.009571,.010064,
-.010064,.009571,
-.010464,.009,
-.010759,.008368,
-.010939,.007695,
-.011,.007,
-.011,-.007,
-.010939,-.007695,
-.010759,-.008368,
-.010464,-.009,
-.010064,-.009571,
-.009571,-.010064,
-.009,-.010464,
-.008368,-.010759,
-.007695,-.010939,
-.007,-.011,
.007,-.011,
.007695,-.010939,
.008368,-.010759,
.009,-.010464,
.009571,-.010064,
.010064,-.009571,
.010464,-.009,
.010759,-.008368,
.010939,-.007695,
.011,-.007,
0.0*
%
%ADD32MACRO32*%
%AMMACRO18*
4,1,40,.007,.011,
-.007,.011,
-.007695,.010939,
-.008368,.010759,
-.009,.010464,
-.009571,.010064,
-.010064,.009571,
-.010464,.009,
-.010759,.008368,
-.010939,.007695,
-.011,.007,
-.011,-.007,
-.010939,-.007695,
-.010759,-.008368,
-.010464,-.009,
-.010064,-.009571,
-.009571,-.010064,
-.009,-.010464,
-.008368,-.010759,
-.007695,-.010939,
-.007,-.011,
.007,-.011,
.007695,-.010939,
.008368,-.010759,
.009,-.010464,
.009571,-.010064,
.010064,-.009571,
.010464,-.009,
.010759,-.008368,
.010939,-.007695,
.011,-.007,
.011,.007,
.010939,.007695,
.010759,.008368,
.010464,.009,
.010064,.009571,
.009571,.010064,
.009,.010464,
.008368,.010759,
.007695,.010939,
.007,.011,
0.0*
%
%ADD18MACRO18*%
%AMMACRO35*
4,1,40,-.012,.008,
-.012,-.008,
-.011939,-.008695,
-.011759,-.009368,
-.011464,-.01,
-.011064,-.010571,
-.010571,-.011064,
-.01,-.011464,
-.009368,-.011759,
-.008695,-.011939,
-.008,-.012,
.008,-.012,
.008695,-.011939,
.009368,-.011759,
.01,-.011464,
.010571,-.011064,
.011064,-.010571,
.011464,-.01,
.011759,-.009368,
.011939,-.008695,
.012,-.008,
.012,.008,
.011939,.008695,
.011759,.009368,
.011464,.01,
.011064,.010571,
.010571,.011064,
.01,.011464,
.009368,.011759,
.008695,.011939,
.008,.012,
-.008,.012,
-.008695,.011939,
-.009368,.011759,
-.01,.011464,
-.010571,.011064,
-.011064,.010571,
-.011464,.01,
-.011759,.009368,
-.011939,.008695,
-.012,.008,
0.0*
%
%ADD35MACRO35*%
%AMMACRO25*
4,1,40,.008,.012,
-.008,.012,
-.008695,.011939,
-.009368,.011759,
-.01,.011464,
-.010571,.011064,
-.011064,.010571,
-.011464,.01,
-.011759,.009368,
-.011939,.008695,
-.012,.008,
-.012,-.008,
-.011939,-.008695,
-.011759,-.009368,
-.011464,-.01,
-.011064,-.010571,
-.010571,-.011064,
-.01,-.011464,
-.009368,-.011759,
-.008695,-.011939,
-.008,-.012,
.008,-.012,
.008695,-.011939,
.009368,-.011759,
.01,-.011464,
.010571,-.011064,
.011064,-.010571,
.011464,-.01,
.011759,-.009368,
.011939,-.008695,
.012,-.008,
.012,.008,
.011939,.008695,
.011759,.009368,
.011464,.01,
.011064,.010571,
.010571,.011064,
.01,.011464,
.009368,.011759,
.008695,.011939,
.008,.012,
0.0*
%
%ADD25MACRO25*%
%AMMACRO47*
4,1,40,-.013,-.017,
.013,-.017,
.013695,-.016939,
.014368,-.016759,
.015,-.016464,
.015571,-.016064,
.016064,-.015571,
.016464,-.015,
.016759,-.014368,
.016939,-.013695,
.017,-.013,
.017,.013,
.016939,.013695,
.016759,.014368,
.016464,.015,
.016064,.015571,
.015571,.016064,
.015,.016464,
.014368,.016759,
.013695,.016939,
.013,.017,
-.013,.017,
-.013695,.016939,
-.014368,.016759,
-.015,.016464,
-.015571,.016064,
-.016064,.015571,
-.016464,.015,
-.016759,.014368,
-.016939,.013695,
-.017,.013,
-.017,-.013,
-.016939,-.013695,
-.016759,-.014368,
-.016464,-.015,
-.016064,-.015571,
-.015571,-.016064,
-.015,-.016464,
-.014368,-.016759,
-.013695,-.016939,
-.013,-.017,
0.0*
%
%ADD47MACRO47*%
%AMMACRO58*
4,1,40,-.017,.013,
-.017,-.013,
-.016939,-.013695,
-.016759,-.014368,
-.016464,-.015,
-.016064,-.015571,
-.015571,-.016064,
-.015,-.016464,
-.014368,-.016759,
-.013695,-.016939,
-.013,-.017,
.013,-.017,
.013695,-.016939,
.014368,-.016759,
.015,-.016464,
.015571,-.016064,
.016064,-.015571,
.016464,-.015,
.016759,-.014368,
.016939,-.013695,
.017,-.013,
.017,.013,
.016939,.013695,
.016759,.014368,
.016464,.015,
.016064,.015571,
.015571,.016064,
.015,.016464,
.014368,.016759,
.013695,.016939,
.013,.017,
-.013,.017,
-.013695,.016939,
-.014368,.016759,
-.015,.016464,
-.015571,.016064,
-.016064,.015571,
-.016464,.015,
-.016759,.014368,
-.016939,.013695,
-.017,.013,
0.0*
%
%ADD58MACRO58*%
%AMMACRO49*
4,1,40,.008,.009,
.008695,.008939,
.009368,.008759,
.01,.008464,
.010571,.008064,
.011064,.007571,
.011464,.007,
.011759,.006368,
.011939,.005695,
.012,.005,
.012,-.005,
.011939,-.005695,
.011759,-.006368,
.011464,-.007,
.011064,-.007571,
.010571,-.008064,
.01,-.008464,
.009368,-.008759,
.008695,-.008939,
.008,-.009,
-.008,-.009,
-.008695,-.008939,
-.009368,-.008759,
-.01,-.008464,
-.010571,-.008064,
-.011064,-.007571,
-.011464,-.007,
-.011759,-.006368,
-.011939,-.005695,
-.012,-.005,
-.012,.005,
-.011939,.005695,
-.011759,.006368,
-.011464,.007,
-.011064,.007571,
-.010571,.008064,
-.01,.008464,
-.009368,.008759,
-.008695,.008939,
-.008,.009,
.008,.009,
0.0*
%
%ADD49MACRO49*%
%AMMACRO33*
4,1,40,.011,-.007,
.011,.007,
.010939,.007695,
.010759,.008368,
.010464,.009,
.010064,.009571,
.009571,.010064,
.009,.010464,
.008368,.010759,
.007695,.010939,
.007,.011,
-.007,.011,
-.007695,.010939,
-.008368,.010759,
-.009,.010464,
-.009571,.010064,
-.010064,.009571,
-.010464,.009,
-.010759,.008368,
-.010939,.007695,
-.011,.007,
-.011,-.007,
-.010939,-.007695,
-.010759,-.008368,
-.010464,-.009,
-.010064,-.009571,
-.009571,-.010064,
-.009,-.010464,
-.008368,-.010759,
-.007695,-.010939,
-.007,-.011,
.007,-.011,
.007695,-.010939,
.008368,-.010759,
.009,-.010464,
.009571,-.010064,
.010064,-.009571,
.010464,-.009,
.010759,-.008368,
.010939,-.007695,
.011,-.007,
0.0*
%
%ADD33MACRO33*%
%AMMACRO19*
4,1,40,.007,.011,
-.007,.011,
-.007695,.010939,
-.008368,.010759,
-.009,.010464,
-.009571,.010064,
-.010064,.009571,
-.010464,.009,
-.010759,.008368,
-.010939,.007695,
-.011,.007,
-.011,-.007,
-.010939,-.007695,
-.010759,-.008368,
-.010464,-.009,
-.010064,-.009571,
-.009571,-.010064,
-.009,-.010464,
-.008368,-.010759,
-.007695,-.010939,
-.007,-.011,
.007,-.011,
.007695,-.010939,
.008368,-.010759,
.009,-.010464,
.009571,-.010064,
.010064,-.009571,
.010464,-.009,
.010759,-.008368,
.010939,-.007695,
.011,-.007,
.011,.007,
.010939,.007695,
.010759,.008368,
.010464,.009,
.010064,.009571,
.009571,.010064,
.009,.010464,
.008368,.010759,
.007695,.010939,
.007,.011,
0.0*
%
%ADD19MACRO19*%
%AMMACRO34*
4,1,40,-.012,.008,
-.012,-.008,
-.011939,-.008695,
-.011759,-.009368,
-.011464,-.01,
-.011064,-.010571,
-.010571,-.011064,
-.01,-.011464,
-.009368,-.011759,
-.008695,-.011939,
-.008,-.012,
.008,-.012,
.008695,-.011939,
.009368,-.011759,
.01,-.011464,
.010571,-.011064,
.011064,-.010571,
.011464,-.01,
.011759,-.009368,
.011939,-.008695,
.012,-.008,
.012,.008,
.011939,.008695,
.011759,.009368,
.011464,.01,
.011064,.010571,
.010571,.011064,
.01,.011464,
.009368,.011759,
.008695,.011939,
.008,.012,
-.008,.012,
-.008695,.011939,
-.009368,.011759,
-.01,.011464,
-.010571,.011064,
-.011064,.010571,
-.011464,.01,
-.011759,.009368,
-.011939,.008695,
-.012,.008,
0.0*
%
%ADD34MACRO34*%
%AMMACRO24*
4,1,40,.008,.012,
-.008,.012,
-.008695,.011939,
-.009368,.011759,
-.01,.011464,
-.010571,.011064,
-.011064,.010571,
-.011464,.01,
-.011759,.009368,
-.011939,.008695,
-.012,.008,
-.012,-.008,
-.011939,-.008695,
-.011759,-.009368,
-.011464,-.01,
-.011064,-.010571,
-.010571,-.011064,
-.01,-.011464,
-.009368,-.011759,
-.008695,-.011939,
-.008,-.012,
.008,-.012,
.008695,-.011939,
.009368,-.011759,
.01,-.011464,
.010571,-.011064,
.011064,-.010571,
.011464,-.01,
.011759,-.009368,
.011939,-.008695,
.012,-.008,
.012,.008,
.011939,.008695,
.011759,.009368,
.011464,.01,
.011064,.010571,
.010571,.011064,
.01,.011464,
.009368,.011759,
.008695,.011939,
.008,.012,
0.0*
%
%ADD24MACRO24*%
%AMMACRO48*
4,1,40,-.013,-.017,
.013,-.017,
.013695,-.016939,
.014368,-.016759,
.015,-.016464,
.015571,-.016064,
.016064,-.015571,
.016464,-.015,
.016759,-.014368,
.016939,-.013695,
.017,-.013,
.017,.013,
.016939,.013695,
.016759,.014368,
.016464,.015,
.016064,.015571,
.015571,.016064,
.015,.016464,
.014368,.016759,
.013695,.016939,
.013,.017,
-.013,.017,
-.013695,.016939,
-.014368,.016759,
-.015,.016464,
-.015571,.016064,
-.016064,.015571,
-.016464,.015,
-.016759,.014368,
-.016939,.013695,
-.017,.013,
-.017,-.013,
-.016939,-.013695,
-.016759,-.014368,
-.016464,-.015,
-.016064,-.015571,
-.015571,-.016064,
-.015,-.016464,
-.014368,-.016759,
-.013695,-.016939,
-.013,-.017,
0.0*
%
%ADD48MACRO48*%
%AMMACRO59*
4,1,40,-.017,.013,
-.017,-.013,
-.016939,-.013695,
-.016759,-.014368,
-.016464,-.015,
-.016064,-.015571,
-.015571,-.016064,
-.015,-.016464,
-.014368,-.016759,
-.013695,-.016939,
-.013,-.017,
.013,-.017,
.013695,-.016939,
.014368,-.016759,
.015,-.016464,
.015571,-.016064,
.016064,-.015571,
.016464,-.015,
.016759,-.014368,
.016939,-.013695,
.017,-.013,
.017,.013,
.016939,.013695,
.016759,.014368,
.016464,.015,
.016064,.015571,
.015571,.016064,
.015,.016464,
.014368,.016759,
.013695,.016939,
.013,.017,
-.013,.017,
-.013695,.016939,
-.014368,.016759,
-.015,.016464,
-.015571,.016064,
-.016064,.015571,
-.016464,.015,
-.016759,.014368,
-.016939,.013695,
-.017,.013,
0.0*
%
%ADD59MACRO59*%
%AMMACRO52*
4,1,40,-.008,-.009,
-.008695,-.008939,
-.009368,-.008759,
-.01,-.008464,
-.010571,-.008064,
-.011064,-.007571,
-.011464,-.007,
-.011759,-.006368,
-.011939,-.005695,
-.012,-.005,
-.012,.005,
-.011939,.005695,
-.011759,.006368,
-.011464,.007,
-.011064,.007571,
-.010571,.008064,
-.01,.008464,
-.009368,.008759,
-.008695,.008939,
-.008,.009,
.008,.009,
.008695,.008939,
.009368,.008759,
.01,.008464,
.010571,.008064,
.011064,.007571,
.011464,.007,
.011759,.006368,
.011939,.005695,
.012,.005,
.012,-.005,
.011939,-.005695,
.011759,-.006368,
.011464,-.007,
.011064,-.007571,
.010571,-.008064,
.01,-.008464,
.009368,-.008759,
.008695,-.008939,
.008,-.009,
-.008,-.009,
0.0*
%
%ADD52MACRO52*%
%ADD12R,.102X.134*%
%ADD57R,.04X.022*%
%ADD29R,.015X.012*%
%ADD28R,.022X.04*%
%ADD17R,.06X.012*%
%ADD54R,.012X.06*%
%ADD15R,.06X.014*%
%ADD55R,.02X.063*%
%ADD39R,.012X.036*%
%ADD38R,.061X.051*%
%ADD50R,.05X.065*%
%ADD13R,.024X.063*%
%ADD45C,.107*%
%ADD60R,.045X.055*%
%ADD27R,.048X.016*%
%ADD51R,.055X.045*%
%ADD16R,.016X.048*%
%ADD56C,.363*%
%AMMACRO37*
4,1,40,-.008,-.012,
.008,-.012,
.008695,-.011939,
.009368,-.011759,
.01,-.011464,
.010571,-.011064,
.011064,-.010571,
.011464,-.01,
.011759,-.009368,
.011939,-.008695,
.012,-.008,
.012,.008,
.011939,.008695,
.011759,.009368,
.011464,.01,
.011064,.010571,
.010571,.011064,
.01,.011464,
.009368,.011759,
.008695,.011939,
.008,.012,
-.008,.012,
-.008695,.011939,
-.009368,.011759,
-.01,.011464,
-.010571,.011064,
-.011064,.010571,
-.011464,.01,
-.011759,.009368,
-.011939,.008695,
-.012,.008,
-.012,-.008,
-.011939,-.008695,
-.011759,-.009368,
-.011464,-.01,
-.011064,-.010571,
-.010571,-.011064,
-.01,-.011464,
-.009368,-.011759,
-.008695,-.011939,
-.008,-.012,
0.0*
%
%ADD37MACRO37*%
%AMMACRO23*
4,1,40,.012,-.008,
.012,.008,
.011939,.008695,
.011759,.009368,
.011464,.01,
.011064,.010571,
.010571,.011064,
.01,.011464,
.009368,.011759,
.008695,.011939,
.008,.012,
-.008,.012,
-.008695,.011939,
-.009368,.011759,
-.01,.011464,
-.010571,.011064,
-.011064,.010571,
-.011464,.01,
-.011759,.009368,
-.011939,.008695,
-.012,.008,
-.012,-.008,
-.011939,-.008695,
-.011759,-.009368,
-.011464,-.01,
-.011064,-.010571,
-.010571,-.011064,
-.01,-.011464,
-.009368,-.011759,
-.008695,-.011939,
-.008,-.012,
.008,-.012,
.008695,-.011939,
.009368,-.011759,
.01,-.011464,
.010571,-.011064,
.011064,-.010571,
.011464,-.01,
.011759,-.009368,
.011939,-.008695,
.012,-.008,
0.0*
%
%ADD23MACRO23*%
%AMMACRO20*
4,1,40,-.007,-.011,
.007,-.011,
.007695,-.010939,
.008368,-.010759,
.009,-.010464,
.009571,-.010064,
.010064,-.009571,
.010464,-.009,
.010759,-.008368,
.010939,-.007695,
.011,-.007,
.011,.007,
.010939,.007695,
.010759,.008368,
.010464,.009,
.010064,.009571,
.009571,.010064,
.009,.010464,
.008368,.010759,
.007695,.010939,
.007,.011,
-.007,.011,
-.007695,.010939,
-.008368,.010759,
-.009,.010464,
-.009571,.010064,
-.010064,.009571,
-.010464,.009,
-.010759,.008368,
-.010939,.007695,
-.011,.007,
-.011,-.007,
-.010939,-.007695,
-.010759,-.008368,
-.010464,-.009,
-.010064,-.009571,
-.009571,-.010064,
-.009,-.010464,
-.008368,-.010759,
-.007695,-.010939,
-.007,-.011,
0.0*
%
%ADD20MACRO20*%
%AMMACRO30*
4,1,40,-.011,.007,
-.011,-.007,
-.010939,-.007695,
-.010759,-.008368,
-.010464,-.009,
-.010064,-.009571,
-.009571,-.010064,
-.009,-.010464,
-.008368,-.010759,
-.007695,-.010939,
-.007,-.011,
.007,-.011,
.007695,-.010939,
.008368,-.010759,
.009,-.010464,
.009571,-.010064,
.010064,-.009571,
.010464,-.009,
.010759,-.008368,
.010939,-.007695,
.011,-.007,
.011,.007,
.010939,.007695,
.010759,.008368,
.010464,.009,
.010064,.009571,
.009571,.010064,
.009,.010464,
.008368,.010759,
.007695,.010939,
.007,.011,
-.007,.011,
-.007695,.010939,
-.008368,.010759,
-.009,.010464,
-.009571,.010064,
-.010064,.009571,
-.010464,.009,
-.010759,.008368,
-.010939,.007695,
-.011,.007,
0.0*
%
%ADD30MACRO30*%
%AMMACRO61*
4,1,40,.017,-.013,
.017,.013,
.016939,.013695,
.016759,.014368,
.016464,.015,
.016064,.015571,
.015571,.016064,
.015,.016464,
.014368,.016759,
.013695,.016939,
.013,.017,
-.013,.017,
-.013695,.016939,
-.014368,.016759,
-.015,.016464,
-.015571,.016064,
-.016064,.015571,
-.016464,.015,
-.016759,.014368,
-.016939,.013695,
-.017,.013,
-.017,-.013,
-.016939,-.013695,
-.016759,-.014368,
-.016464,-.015,
-.016064,-.015571,
-.015571,-.016064,
-.015,-.016464,
-.014368,-.016759,
-.013695,-.016939,
-.013,-.017,
.013,-.017,
.013695,-.016939,
.014368,-.016759,
.015,-.016464,
.015571,-.016064,
.016064,-.015571,
.016464,-.015,
.016759,-.014368,
.016939,-.013695,
.017,-.013,
0.0*
%
%ADD61MACRO61*%
%AMMACRO41*
4,1,40,.013,.017,
-.013,.017,
-.013695,.016939,
-.014368,.016759,
-.015,.016464,
-.015571,.016064,
-.016064,.015571,
-.016464,.015,
-.016759,.014368,
-.016939,.013695,
-.017,.013,
-.017,-.013,
-.016939,-.013695,
-.016759,-.014368,
-.016464,-.015,
-.016064,-.015571,
-.015571,-.016064,
-.015,-.016464,
-.014368,-.016759,
-.013695,-.016939,
-.013,-.017,
.013,-.017,
.013695,-.016939,
.014368,-.016759,
.015,-.016464,
.015571,-.016064,
.016064,-.015571,
.016464,-.015,
.016759,-.014368,
.016939,-.013695,
.017,-.013,
.017,.013,
.016939,.013695,
.016759,.014368,
.016464,.015,
.016064,.015571,
.015571,.016064,
.015,.016464,
.014368,.016759,
.013695,.016939,
.013,.017,
0.0*
%
%ADD41MACRO41*%
%AMMACRO64*
4,1,40,-.008,-.009,
-.008695,-.008939,
-.009368,-.008759,
-.01,-.008464,
-.010571,-.008064,
-.011064,-.007571,
-.011464,-.007,
-.011759,-.006368,
-.011939,-.005695,
-.012,-.005,
-.012,.005,
-.011939,.005695,
-.011759,.006368,
-.011464,.007,
-.011064,.007571,
-.010571,.008064,
-.01,.008464,
-.009368,.008759,
-.008695,.008939,
-.008,.009,
.008,.009,
.008695,.008939,
.009368,.008759,
.01,.008464,
.010571,.008064,
.011064,.007571,
.011464,.007,
.011759,.006368,
.011939,.005695,
.012,.005,
.012,-.005,
.011939,-.005695,
.011759,-.006368,
.011464,-.007,
.011064,-.007571,
.010571,-.008064,
.01,-.008464,
.009368,-.008759,
.008695,-.008939,
.008,-.009,
-.008,-.009,
0.0*
%
%ADD64MACRO64*%
%AMMACRO36*
4,1,40,-.008,-.012,
.008,-.012,
.008695,-.011939,
.009368,-.011759,
.01,-.011464,
.010571,-.011064,
.011064,-.010571,
.011464,-.01,
.011759,-.009368,
.011939,-.008695,
.012,-.008,
.012,.008,
.011939,.008695,
.011759,.009368,
.011464,.01,
.011064,.010571,
.010571,.011064,
.01,.011464,
.009368,.011759,
.008695,.011939,
.008,.012,
-.008,.012,
-.008695,.011939,
-.009368,.011759,
-.01,.011464,
-.010571,.011064,
-.011064,.010571,
-.011464,.01,
-.011759,.009368,
-.011939,.008695,
-.012,.008,
-.012,-.008,
-.011939,-.008695,
-.011759,-.009368,
-.011464,-.01,
-.011064,-.010571,
-.010571,-.011064,
-.01,-.011464,
-.009368,-.011759,
-.008695,-.011939,
-.008,-.012,
0.0*
%
%ADD36MACRO36*%
%AMMACRO22*
4,1,40,.012,-.008,
.012,.008,
.011939,.008695,
.011759,.009368,
.011464,.01,
.011064,.010571,
.010571,.011064,
.01,.011464,
.009368,.011759,
.008695,.011939,
.008,.012,
-.008,.012,
-.008695,.011939,
-.009368,.011759,
-.01,.011464,
-.010571,.011064,
-.011064,.010571,
-.011464,.01,
-.011759,.009368,
-.011939,.008695,
-.012,.008,
-.012,-.008,
-.011939,-.008695,
-.011759,-.009368,
-.011464,-.01,
-.011064,-.010571,
-.010571,-.011064,
-.01,-.011464,
-.009368,-.011759,
-.008695,-.011939,
-.008,-.012,
.008,-.012,
.008695,-.011939,
.009368,-.011759,
.01,-.011464,
.010571,-.011064,
.011064,-.010571,
.011464,-.01,
.011759,-.009368,
.011939,-.008695,
.012,-.008,
0.0*
%
%ADD22MACRO22*%
%AMMACRO21*
4,1,40,-.007,-.011,
.007,-.011,
.007695,-.010939,
.008368,-.010759,
.009,-.010464,
.009571,-.010064,
.010064,-.009571,
.010464,-.009,
.010759,-.008368,
.010939,-.007695,
.011,-.007,
.011,.007,
.010939,.007695,
.010759,.008368,
.010464,.009,
.010064,.009571,
.009571,.010064,
.009,.010464,
.008368,.010759,
.007695,.010939,
.007,.011,
-.007,.011,
-.007695,.010939,
-.008368,.010759,
-.009,.010464,
-.009571,.010064,
-.010064,.009571,
-.010464,.009,
-.010759,.008368,
-.010939,.007695,
-.011,.007,
-.011,-.007,
-.010939,-.007695,
-.010759,-.008368,
-.010464,-.009,
-.010064,-.009571,
-.009571,-.010064,
-.009,-.010464,
-.008368,-.010759,
-.007695,-.010939,
-.007,-.011,
0.0*
%
%ADD21MACRO21*%
%AMMACRO31*
4,1,40,-.011,.007,
-.011,-.007,
-.010939,-.007695,
-.010759,-.008368,
-.010464,-.009,
-.010064,-.009571,
-.009571,-.010064,
-.009,-.010464,
-.008368,-.010759,
-.007695,-.010939,
-.007,-.011,
.007,-.011,
.007695,-.010939,
.008368,-.010759,
.009,-.010464,
.009571,-.010064,
.010064,-.009571,
.010464,-.009,
.010759,-.008368,
.010939,-.007695,
.011,-.007,
.011,.007,
.010939,.007695,
.010759,.008368,
.010464,.009,
.010064,.009571,
.009571,.010064,
.009,.010464,
.008368,.010759,
.007695,.010939,
.007,.011,
-.007,.011,
-.007695,.010939,
-.008368,.010759,
-.009,.010464,
-.009571,.010064,
-.010064,.009571,
-.010464,.009,
-.010759,.008368,
-.010939,.007695,
-.011,.007,
0.0*
%
%ADD31MACRO31*%
%ADD65C,.006*%
G75*
%LPD*%
G75*
G54D10*
X-18898Y16741D03*
X-17506Y723144D03*
X13800Y60400D03*
X114497Y137176D03*
X115583Y329366D03*
X114497Y525759D03*
X115583Y717948D03*
X218800Y337200D03*
X365520Y-1413D03*
X366606Y190776D03*
X365520Y387169D03*
X366606Y579359D03*
X494816Y713716D03*
G54D20*
X25600Y70800D03*
X36931Y66704D03*
X56700Y32300D03*
X41700Y118500D03*
X39200Y91400D03*
X48200Y187610D03*
Y195610D03*
X50862Y154167D03*
X111600Y24900D03*
X133400Y24000D03*
X79100Y47000D03*
X180700Y70200D03*
X174300Y48800D03*
X220682Y49139D03*
X192200Y90000D03*
X218300Y119000D03*
X219100Y181300D03*
Y197300D03*
X217800Y206700D03*
X210567Y283448D03*
G54D11*
X-5631Y5915D03*
X-4866Y709193D03*
X12000Y342400D03*
X211700Y17700D03*
X180200Y342500D03*
X489553Y2518D03*
G54D21*
X22200Y70800D03*
X33531Y66704D03*
X53300Y32300D03*
X38300Y118500D03*
X35800Y91400D03*
X44800Y187610D03*
Y195610D03*
X47462Y154167D03*
X108200Y24900D03*
X130000Y24000D03*
X75700Y47000D03*
X177300Y70200D03*
X170900Y48800D03*
X217282Y49139D03*
X188800Y90000D03*
X214900Y119000D03*
X215700Y181300D03*
Y197300D03*
X214400Y206700D03*
X207167Y283448D03*
G54D30*
X33700Y118100D03*
X12100Y81300D03*
X28200Y117900D03*
X7200Y199300D03*
X9050Y191800D03*
X48300Y172100D03*
X54492Y181924D03*
X76500Y51200D03*
X80600D03*
X79200Y70100D03*
Y62600D03*
X79604Y80369D03*
X188250Y59096D03*
X222500Y38800D03*
X219378Y25905D03*
X205500Y48800D03*
X215300Y53200D03*
X201500Y48800D03*
X218832Y124859D03*
X168936Y76013D03*
X205500Y172700D03*
X209900D03*
G54D12*
X23760Y-1772D03*
X208918D03*
G54D31*
X33700Y121500D03*
X12100Y84700D03*
X28200Y121300D03*
X7200Y202700D03*
X9050Y195200D03*
X48300Y175500D03*
X54492Y185324D03*
X76500Y54600D03*
X80600D03*
X79200Y66000D03*
Y73500D03*
X79604Y83769D03*
X188250Y62496D03*
X222500Y42200D03*
X219378Y29305D03*
X205500Y52200D03*
X215300Y56600D03*
X201500Y52200D03*
X218832Y128259D03*
X168936Y79413D03*
X205500Y176100D03*
X209900D03*
G54D22*
X41000Y48600D03*
X40200Y58800D03*
X59700Y38600D03*
X164900Y48200D03*
X214500Y201900D03*
G54D13*
X68819Y6299D03*
X63819D03*
X58819D03*
X53819D03*
X143839D03*
X138839D03*
X133839D03*
X128839D03*
X123839D03*
X118839D03*
X113839D03*
X108839D03*
X83819D03*
X78819D03*
X73819D03*
X178839D03*
X173839D03*
X168839D03*
X163839D03*
X158839D03*
X153839D03*
X148839D03*
G54D40*
X37283Y173228D03*
X27283D03*
X193583D03*
X183583D03*
G54D41*
X33809Y159738D03*
X6797Y255079D03*
Y250327D03*
X6793Y245566D03*
X188783Y156500D03*
G54D23*
X37400Y48600D03*
X36600Y58800D03*
X56100Y38600D03*
X161300Y48200D03*
X210900Y201900D03*
G54D50*
X25000Y277000D03*
X36000D03*
X213790Y276128D03*
X202790D03*
G54D32*
X12100Y77200D03*
X23300Y109200D03*
X52400Y175500D03*
X50272Y288472D03*
X98071Y51625D03*
X75604Y83769D03*
X219500Y56600D03*
X192500Y70200D03*
X218300Y39200D03*
X215378Y29305D03*
X209522Y52212D03*
X180800Y108300D03*
X215516Y135785D03*
X223200Y188750D03*
Y196300D03*
X220723Y291345D03*
G54D14*
X41752Y5118D03*
X22440Y303149D03*
X32283D03*
X42126D03*
X22440Y322835D03*
X32283D03*
X42126D03*
X190926Y5118D03*
X182677Y303149D03*
X192520D03*
X202363D03*
X182677Y322835D03*
X192520D03*
X202363D03*
G54D51*
X11103Y232047D03*
Y239647D03*
G54D60*
X178720Y276481D03*
X186320D03*
G54D15*
X69500Y65420D03*
Y67980D03*
Y70540D03*
X47300D03*
Y67980D03*
Y65420D03*
X69500Y73100D03*
Y75660D03*
Y78220D03*
Y80780D03*
Y83340D03*
Y85900D03*
Y88460D03*
Y91020D03*
Y93580D03*
X47300D03*
Y91020D03*
Y88460D03*
Y85900D03*
Y83340D03*
Y80780D03*
Y78220D03*
Y75660D03*
Y73100D03*
X34400Y84340D03*
Y81780D03*
Y79220D03*
Y76660D03*
X21600D03*
Y79220D03*
Y81780D03*
Y84340D03*
X37190Y196840D03*
Y194280D03*
Y191720D03*
Y189160D03*
X21010D03*
Y191720D03*
Y194280D03*
Y196840D03*
X220600Y61420D03*
Y63980D03*
Y66540D03*
Y69100D03*
Y71660D03*
X198400D03*
Y69100D03*
Y66540D03*
Y63980D03*
Y61420D03*
X220600Y74220D03*
Y76780D03*
Y79340D03*
Y81900D03*
Y84460D03*
Y87020D03*
Y89580D03*
X198400D03*
Y87020D03*
Y84460D03*
Y81900D03*
Y79340D03*
Y76780D03*
Y74220D03*
X187400Y83340D03*
Y80780D03*
Y78220D03*
Y75660D03*
X174600D03*
Y78220D03*
Y80780D03*
Y83340D03*
X207590Y195940D03*
Y193380D03*
Y190820D03*
Y188260D03*
X191410D03*
Y190820D03*
Y193380D03*
Y195940D03*
G54D24*
X52600Y27100D03*
X104300Y28500D03*
X197760Y56827D03*
X215800Y107610D03*
X192724Y80830D03*
G54D33*
X12100Y73800D03*
X23300Y105800D03*
X52400Y172100D03*
X50272Y285072D03*
X98071Y48225D03*
X75604Y80369D03*
X219500Y53200D03*
X192500Y66800D03*
X218300Y35800D03*
X215378Y25905D03*
X209522Y48812D03*
X180800Y104900D03*
X215516Y132385D03*
X223200Y185350D03*
Y192900D03*
X220723Y287945D03*
G54D42*
X39409Y159738D03*
X12397Y255079D03*
Y250327D03*
X12393Y245566D03*
X194383Y156500D03*
G54D61*
X186454Y288824D03*
X191054D03*
X195654D03*
G54D16*
X47060Y32450D03*
X44500D03*
X41940D03*
Y25950D03*
X47060D03*
X62440Y25750D03*
X65000D03*
X67560D03*
Y32250D03*
X62440D03*
G54D52*
X7985Y225487D03*
G54D34*
X30742Y103542D03*
X53700Y118300D03*
X49018Y199384D03*
X106000Y51800D03*
X116500Y27400D03*
X214800Y115200D03*
G54D25*
X52600Y23500D03*
X104300Y24900D03*
X197760Y53227D03*
X215800Y104010D03*
X192724Y77230D03*
G54D43*
X13200Y187900D03*
X183653Y191058D03*
G54D17*
X48150Y45565D03*
Y47530D03*
Y49500D03*
Y51470D03*
Y53435D03*
X64450D03*
Y51470D03*
Y49500D03*
Y47530D03*
Y45565D03*
X190850Y34565D03*
Y36530D03*
Y38500D03*
Y40470D03*
Y42435D03*
X207150D03*
Y40470D03*
Y38500D03*
Y36530D03*
Y34565D03*
G54D35*
X34342Y103542D03*
X57300Y118300D03*
X52618Y199384D03*
X109600Y51800D03*
X120100Y27400D03*
X218400Y115200D03*
G54D26*
X61000Y60500D03*
X14100Y48700D03*
X16813Y69474D03*
X51800Y38000D03*
X41300Y44400D03*
X56000Y60500D03*
X41300Y62600D03*
X49900Y16349D03*
X31600Y48100D03*
X29400Y58900D03*
X29650Y66500D03*
X67300Y38740D03*
X44416Y38922D03*
X66200Y60200D03*
X40631Y67104D03*
X71500Y53200D03*
X24900Y89600D03*
X12900Y107500D03*
X15800Y78400D03*
X16174Y73626D03*
X27042Y95162D03*
X45314Y102920D03*
X67282Y114234D03*
X69150Y105600D03*
X37000Y113300D03*
X41200Y95100D03*
X45900Y118700D03*
X55300Y165138D03*
X46000Y161800D03*
X17323Y159819D03*
X29232Y159877D03*
X49322Y183538D03*
X47699Y179634D03*
X12200Y201200D03*
X13646Y195250D03*
X11636Y227035D03*
X55800Y292900D03*
X43926Y277000D03*
X136400Y46500D03*
X77173Y23627D03*
X73400Y32000D03*
X145883Y54000D03*
X148558Y43046D03*
X75100Y68300D03*
X108300Y28700D03*
X112600D03*
X126100Y50300D03*
X121700D03*
X101800Y51800D03*
X116850Y34100D03*
X101200Y36500D03*
X129200Y27800D03*
X78600Y58500D03*
X75604Y76400D03*
X219082Y20786D03*
X178843Y62700D03*
X151336Y62300D03*
X193710Y20009D03*
X181167Y22264D03*
X172392Y18892D03*
X172328Y24231D03*
X205700Y55900D03*
X201600Y57100D03*
X161500Y65600D03*
X154424Y40024D03*
X183300Y54700D03*
X197500Y48750D03*
X178700Y52500D03*
X177637Y34565D03*
X192366Y61922D03*
X217732Y42900D03*
X223378Y30635D03*
X211300Y56100D03*
X214033Y44990D03*
X180600Y88400D03*
X165206Y110272D03*
X175766Y121643D03*
X164700Y82300D03*
X162610Y75430D03*
X171900Y105000D03*
X215000Y122900D03*
X182800Y92100D03*
X180800Y114300D03*
X223900Y203200D03*
X181800Y159400D03*
X215600Y151200D03*
X206763Y165082D03*
X218534Y202560D03*
X216100Y190400D03*
X211900Y182300D03*
X201900Y182100D03*
X207400Y182300D03*
X170617Y271803D03*
X220891Y296541D03*
X213762Y241107D03*
G54D44*
X38189Y220472D03*
X28346Y222440D03*
X38189Y251968D03*
Y244094D03*
Y236220D03*
Y228346D03*
X28346Y232283D03*
Y240157D03*
Y250000D03*
X12598Y312992D03*
X51968D03*
X198426Y220472D03*
X188583Y222440D03*
X198426Y251968D03*
Y244094D03*
Y236220D03*
Y228346D03*
X188583Y232283D03*
Y240157D03*
Y250000D03*
X172835Y312992D03*
X212205D03*
G54D53*
G01X-351984Y-328833D02*
X-383984D01*
G01X-351984Y-344833D02*
Y-424833D01*
G01D02*
X998716D01*
G01X-355984Y-328833D02*
G02I-12000J0D01*
G01X-361134D02*
G02I-6850J0D01*
G01X-367984Y-344833D02*
Y-312833D01*
G01X-351984Y-344833D02*
X998716D01*
G01X-351984Y-380333D02*
X998716D01*
G01X211216Y-344833D02*
Y-424833D01*
G01X348716Y-344833D02*
Y-424833D01*
G01X463716Y-344833D02*
Y-424833D01*
G01X631216Y-344833D02*
Y-424833D01*
G01X801216Y-344833D02*
Y-424833D01*
G01X998716Y-344833D02*
Y-424833D01*
G01X1026716Y-328833D02*
G02I-12000J0D01*
G01X1021566D02*
G02I-6850J0D01*
G01X1014716Y-344833D02*
Y-312833D01*
G01X1030716Y-328833D02*
X998716D01*
X16977Y244294D03*
X16984Y248748D03*
X96200Y16400D03*
X133200Y17751D03*
X107506Y16719D03*
X116430Y16569D03*
X191391Y278906D03*
X195939Y278959D03*
G54D62*
X186454Y283224D03*
X191054D03*
X195654D03*
G54D36*
X15900Y82800D03*
X39900Y80500D03*
X100900Y40600D03*
X132600Y34100D03*
Y47000D03*
X176300Y40400D03*
X183500Y39700D03*
X168966Y83430D03*
G54D27*
X51750Y113060D03*
Y110500D03*
Y107940D03*
X58250D03*
Y113060D03*
X163452Y40642D03*
Y38082D03*
Y35522D03*
X169952D03*
Y40642D03*
X170750Y54440D03*
Y57000D03*
Y59560D03*
X164250D03*
Y54440D03*
X203050Y108060D03*
Y105500D03*
Y102940D03*
X209550D03*
Y108060D03*
G54D45*
X40157Y211023D03*
X24409D03*
X40157Y261417D03*
X24409D03*
X200394Y211023D03*
X184646D03*
X200394Y261417D03*
X184646D03*
G54D54*
X106048Y44885D03*
X108018D03*
X109988D03*
X111958D03*
Y35685D03*
X109988D03*
X108018D03*
X106048D03*
X127770Y34391D03*
X125800D03*
X123830D03*
X121860D03*
Y43591D03*
X123830D03*
X125800D03*
X127770D03*
G54D18*
X33500Y62600D03*
X48300Y59700D03*
X29700Y70800D03*
X70100Y60500D03*
X37331Y70804D03*
X38042Y109358D03*
X44800Y191610D03*
X30300Y284000D03*
X122300Y54000D03*
X97601Y32537D03*
X116600Y23500D03*
X184800Y70200D03*
X169487Y70136D03*
X198520Y113600D03*
X192771Y121500D03*
X215700Y185300D03*
G54D63*
X178741Y282699D03*
G54D64*
Y285699D03*
G54D37*
X15900Y86400D03*
X39900Y84100D03*
X100900Y44200D03*
X132600Y37700D03*
Y50600D03*
X176300Y44000D03*
X183500Y43300D03*
X168966Y87030D03*
G54D55*
X105788Y6299D03*
X102638D03*
X99489D03*
X96339D03*
X93189D03*
X90040D03*
X86890D03*
G54D28*
X17700Y106250D03*
Y112250D03*
X15300Y288650D03*
Y282650D03*
X222189Y316231D03*
Y310231D03*
G54D19*
X36900Y62600D03*
X51700Y59700D03*
X33100Y70800D03*
X40731Y70804D03*
X41442Y109358D03*
X48200Y191610D03*
X33700Y284000D03*
X125700Y54000D03*
X101001Y32537D03*
X120000Y23500D03*
X73500Y60500D03*
X188200Y70200D03*
X172887Y70136D03*
X201920Y113600D03*
X196171Y121500D03*
X219100Y185300D03*
G54D46*
X10519Y217435D03*
X8392Y207860D03*
X178563Y197014D03*
X178695Y185153D03*
G54D65*
G01X-322688Y-405500D02*
X-321814Y-404625D01*
X-321159Y-403167D01*
X-320722Y-401124D01*
X-321159Y-399375D01*
X-322032Y-398208D01*
X-323561Y-397333D01*
X-329456D01*
Y-414833D01*
X-322251D01*
X-320722Y-413667D01*
X-319849Y-411916D01*
X-319412Y-409875D01*
X-319849Y-407833D01*
X-321159Y-406083D01*
X-322688Y-405500D01*
X-329456D01*
G01X-309991Y-414833D02*
Y-403167D01*
G01Y-405500D02*
X-308899Y-404333D01*
X-307807Y-403458D01*
X-306279Y-403167D01*
X-305188Y-403458D01*
X-303877Y-404333D01*
G01X-294019Y-420083D02*
X-292709Y-420666D01*
X-290962Y-420083D01*
X-289871Y-418917D01*
X-288997Y-417458D01*
X-287688Y-412792D01*
X-284849Y-403167D01*
G01X-291836D02*
X-287688Y-412792D01*
G01X-268441Y-404625D02*
X-269969Y-403458D01*
X-271279Y-403167D01*
X-273026Y-403750D01*
X-274336Y-404916D01*
X-275209Y-406958D01*
X-275428Y-409000D01*
X-275209Y-411042D01*
X-274336Y-412792D01*
X-273026Y-414250D01*
X-271279Y-414833D01*
X-269751Y-414250D01*
X-268441Y-413083D01*
G01X-257709Y-406958D02*
X-250722D01*
X-251377Y-404916D01*
X-252469Y-403750D01*
X-253997Y-403167D01*
X-255526Y-403458D01*
X-256836Y-404333D01*
X-257709Y-406375D01*
X-258146Y-408125D01*
Y-409875D01*
X-257709Y-411625D01*
X-256617Y-413375D01*
X-255307Y-414541D01*
X-253779Y-414833D01*
X-252251Y-414250D01*
X-250722Y-412500D01*
G01X-214631Y-398792D02*
X-215941Y-397916D01*
X-217469Y-397333D01*
X-219216D01*
X-221181Y-398208D01*
X-222709Y-399666D01*
X-223801Y-401417D01*
X-224674Y-404333D01*
X-224893Y-406958D01*
X-224456Y-409583D01*
X-223801Y-411333D01*
X-222491Y-413083D01*
X-220962Y-414250D01*
X-219434Y-414833D01*
X-217906D01*
X-216377Y-414250D01*
X-215067Y-413375D01*
X-213975Y-412209D01*
G01X-198004Y-414833D02*
Y-403167D01*
G01Y-405208D02*
X-198877Y-404042D01*
X-200188Y-403458D01*
X-201716Y-403167D01*
X-203244Y-403750D01*
X-204554Y-404916D01*
X-205428Y-406666D01*
X-205864Y-409000D01*
X-205428Y-411333D01*
X-204554Y-413083D01*
X-203244Y-414250D01*
X-201716Y-414833D01*
X-200188Y-414541D01*
X-198877Y-413667D01*
X-198004Y-412500D01*
G01X-188146Y-414833D02*
Y-403167D01*
G01Y-406083D02*
X-187272Y-404625D01*
X-185962Y-403458D01*
X-184216Y-403167D01*
X-182688Y-403458D01*
X-181377Y-404625D01*
X-180722Y-406666D01*
Y-414833D01*
G01X-171519Y-420083D02*
X-170209Y-420666D01*
X-168462Y-420083D01*
X-167371Y-418917D01*
X-166497Y-417458D01*
X-165188Y-412792D01*
X-162349Y-403167D01*
G01X-169336D02*
X-165188Y-412792D01*
G01X-149434Y-414833D02*
X-150744Y-414541D01*
X-152054Y-413375D01*
X-152928Y-411333D01*
X-153364Y-409000D01*
X-152928Y-406666D01*
X-152054Y-404625D01*
X-150744Y-403458D01*
X-149434Y-403167D01*
X-148124Y-403458D01*
X-146814Y-404625D01*
X-145941Y-406666D01*
X-145722Y-409000D01*
X-145941Y-411333D01*
X-146814Y-413375D01*
X-148124Y-414541D01*
X-149434Y-414833D01*
G01X-135646D02*
Y-403167D01*
G01Y-406083D02*
X-134772Y-404625D01*
X-133462Y-403458D01*
X-131716Y-403167D01*
X-130188Y-403458D01*
X-128877Y-404625D01*
X-128222Y-406666D01*
Y-414833D01*
G01X-101082D02*
Y-397333D01*
X-92786D01*
G01X-95842Y-405791D02*
X-101082D01*
G01X-82491Y-414833D02*
Y-403167D01*
G01Y-405500D02*
X-81399Y-404333D01*
X-80307Y-403458D01*
X-78779Y-403167D01*
X-77688Y-403458D01*
X-76377Y-404333D01*
G01X-61934Y-414833D02*
X-63244Y-414541D01*
X-64554Y-413375D01*
X-65428Y-411333D01*
X-65864Y-409000D01*
X-65428Y-406666D01*
X-64554Y-404625D01*
X-63244Y-403458D01*
X-61934Y-403167D01*
X-60624Y-403458D01*
X-59314Y-404625D01*
X-58441Y-406666D01*
X-58222Y-409000D01*
X-58441Y-411333D01*
X-59314Y-413375D01*
X-60624Y-414541D01*
X-61934Y-414833D01*
G01X-48146D02*
Y-403167D01*
G01Y-406083D02*
X-47272Y-404625D01*
X-45962Y-403458D01*
X-44216Y-403167D01*
X-42688Y-403458D01*
X-41377Y-404625D01*
X-40722Y-406666D01*
Y-414833D01*
G01X-26934Y-397333D02*
Y-414833D01*
G01X-29991Y-403167D02*
X-23877D01*
G01X3699Y-414833D02*
Y-397333D01*
X8939D01*
X10686Y-398208D01*
X11996Y-400250D01*
X12433Y-402583D01*
X11996Y-404916D01*
X10904Y-406666D01*
X8939Y-407542D01*
X3699D01*
G01X29496Y-414833D02*
Y-403167D01*
G01Y-405208D02*
X28623Y-404042D01*
X27312Y-403458D01*
X25784Y-403167D01*
X24256Y-403750D01*
X22946Y-404916D01*
X22072Y-406666D01*
X21636Y-409000D01*
X22072Y-411333D01*
X22946Y-413083D01*
X24256Y-414250D01*
X25784Y-414833D01*
X27312Y-414541D01*
X28623Y-413667D01*
X29496Y-412500D01*
G01X39354Y-414833D02*
Y-403167D01*
G01Y-406083D02*
X40228Y-404625D01*
X41538Y-403458D01*
X43284Y-403167D01*
X44812Y-403458D01*
X46123Y-404625D01*
X46778Y-406666D01*
Y-414833D01*
G01X57291Y-406958D02*
X64278D01*
X63623Y-404916D01*
X62531Y-403750D01*
X61003Y-403167D01*
X59474Y-403458D01*
X58164Y-404333D01*
X57291Y-406375D01*
X56854Y-408125D01*
Y-409875D01*
X57291Y-411625D01*
X58383Y-413375D01*
X59693Y-414541D01*
X61221Y-414833D01*
X62749Y-414250D01*
X64278Y-412500D01*
G01X78066Y-414833D02*
Y-397333D01*
G01X114812Y-405500D02*
X115686Y-404625D01*
X116341Y-403167D01*
X116778Y-401124D01*
X116341Y-399375D01*
X115468Y-398208D01*
X113939Y-397333D01*
X108044D01*
Y-414833D01*
X115249D01*
X116778Y-413667D01*
X117651Y-411916D01*
X118088Y-409875D01*
X117651Y-407833D01*
X116341Y-406083D01*
X114812Y-405500D01*
X108044D01*
G01X130566Y-414833D02*
X129256Y-414541D01*
X127946Y-413375D01*
X127072Y-411333D01*
X126636Y-409000D01*
X127072Y-406666D01*
X127946Y-404625D01*
X129256Y-403458D01*
X130566Y-403167D01*
X131876Y-403458D01*
X133186Y-404625D01*
X134059Y-406666D01*
X134278Y-409000D01*
X134059Y-411333D01*
X133186Y-413375D01*
X131876Y-414541D01*
X130566Y-414833D01*
G01X151996D02*
Y-403167D01*
G01Y-405208D02*
X151123Y-404042D01*
X149812Y-403458D01*
X148284Y-403167D01*
X146756Y-403750D01*
X145446Y-404916D01*
X144572Y-406666D01*
X144136Y-409000D01*
X144572Y-411333D01*
X145446Y-413083D01*
X146756Y-414250D01*
X148284Y-414833D01*
X149812Y-414541D01*
X151123Y-413667D01*
X151996Y-412500D01*
G01X162509Y-414833D02*
Y-403167D01*
G01Y-405500D02*
X163601Y-404333D01*
X164693Y-403458D01*
X166221Y-403167D01*
X167312Y-403458D01*
X168623Y-404333D01*
G01X186996Y-397333D02*
Y-414833D01*
G01Y-412209D02*
X186123Y-413667D01*
X184812Y-414541D01*
X183284Y-414833D01*
X181538Y-414250D01*
X180228Y-412792D01*
X179354Y-411042D01*
X179136Y-409000D01*
X179354Y-406958D01*
X180228Y-405208D01*
X181538Y-403750D01*
X183284Y-403167D01*
X184812Y-403458D01*
X185904Y-404042D01*
X186996Y-405208D01*
G01X-111361Y-369833D02*
Y-352333D01*
X-105684Y-366916D01*
X-100007Y-352333D01*
Y-369833D01*
G01X-88184D02*
X-89494Y-369541D01*
X-90804Y-368375D01*
X-91678Y-366333D01*
X-92114Y-364000D01*
X-91678Y-361666D01*
X-90804Y-359625D01*
X-89494Y-358458D01*
X-88184Y-358167D01*
X-86874Y-358458D01*
X-85564Y-359625D01*
X-84691Y-361666D01*
X-84472Y-364000D01*
X-84691Y-366333D01*
X-85564Y-368375D01*
X-86874Y-369541D01*
X-88184Y-369833D01*
G01X-66754Y-352333D02*
Y-369833D01*
G01Y-367209D02*
X-67627Y-368667D01*
X-68938Y-369541D01*
X-70466Y-369833D01*
X-72212Y-369250D01*
X-73522Y-367792D01*
X-74396Y-366042D01*
X-74614Y-364000D01*
X-74396Y-361958D01*
X-73522Y-360208D01*
X-72212Y-358750D01*
X-70466Y-358167D01*
X-68938Y-358458D01*
X-67846Y-359042D01*
X-66754Y-360208D01*
G01X-56459Y-361958D02*
X-49472D01*
X-50127Y-359916D01*
X-51219Y-358750D01*
X-52747Y-358167D01*
X-54276Y-358458D01*
X-55586Y-359333D01*
X-56459Y-361375D01*
X-56896Y-363125D01*
Y-364875D01*
X-56459Y-366625D01*
X-55367Y-368375D01*
X-54057Y-369541D01*
X-52529Y-369833D01*
X-51001Y-369250D01*
X-49472Y-367500D01*
G01X-35684Y-369833D02*
Y-352333D01*
G01X244916Y-414833D02*
Y-397333D01*
X242296Y-400833D01*
G01Y-414833D02*
X247536D01*
G01X258268Y-407542D02*
X259796Y-405500D01*
X261106Y-404333D01*
X262853Y-403750D01*
X264381Y-404333D01*
X265473Y-405500D01*
X266346Y-407250D01*
X266564Y-409291D01*
X266346Y-411042D01*
X265473Y-412792D01*
X264162Y-414250D01*
X262634Y-414833D01*
X260888Y-414250D01*
X259359Y-412500D01*
X258486Y-409875D01*
X258268Y-406958D01*
X258704Y-403167D01*
X259359Y-401124D01*
X260451Y-399083D01*
X261979Y-397625D01*
X263508Y-397333D01*
X265036Y-397916D01*
X266128Y-399375D01*
G01X275113Y-411333D02*
X276422Y-413375D01*
X278169Y-414541D01*
X280134Y-414833D01*
X281881Y-414541D01*
X283628Y-413083D01*
X284719Y-411333D01*
X284938Y-409583D01*
X284501Y-407542D01*
X282973Y-406083D01*
X281444Y-405500D01*
X279479D01*
G01X281444D02*
X282754Y-404625D01*
X283846Y-403167D01*
X284283Y-401417D01*
X283846Y-399666D01*
X282754Y-398208D01*
X280789Y-397333D01*
X278824Y-397625D01*
X276859Y-398792D01*
G01X293268Y-407542D02*
X294796Y-405500D01*
X296106Y-404333D01*
X297853Y-403750D01*
X299381Y-404333D01*
X300473Y-405500D01*
X301346Y-407250D01*
X301564Y-409291D01*
X301346Y-411042D01*
X300473Y-412792D01*
X299162Y-414250D01*
X297634Y-414833D01*
X295888Y-414250D01*
X294359Y-412500D01*
X293486Y-409875D01*
X293268Y-406958D01*
X293704Y-403167D01*
X294359Y-401124D01*
X295451Y-399083D01*
X296979Y-397625D01*
X298508Y-397333D01*
X300036Y-397916D01*
X301128Y-399375D01*
G01X311204Y-412792D02*
X312733Y-414250D01*
X314479Y-414833D01*
X316226Y-414250D01*
X317754Y-412500D01*
X318846Y-409875D01*
X319283Y-407250D01*
Y-404042D01*
X318846Y-401417D01*
X317754Y-399083D01*
X316444Y-397916D01*
X314916Y-397333D01*
X313169Y-397916D01*
X311859Y-399083D01*
X310986Y-400833D01*
X310549Y-403167D01*
X310986Y-405208D01*
X312078Y-407250D01*
X313388Y-408417D01*
X314916Y-408708D01*
X316662Y-408125D01*
X317973Y-406666D01*
X319283Y-404042D01*
G01X231799Y-369833D02*
Y-352333D01*
X237039D01*
X238786Y-353208D01*
X240096Y-355250D01*
X240533Y-357583D01*
X240096Y-359916D01*
X239004Y-361666D01*
X237039Y-362542D01*
X231799D01*
G01X258469Y-353792D02*
X257159Y-352916D01*
X255631Y-352333D01*
X253884D01*
X251919Y-353208D01*
X250391Y-354666D01*
X249299Y-356417D01*
X248426Y-359333D01*
X248207Y-361958D01*
X248644Y-364583D01*
X249299Y-366333D01*
X250609Y-368083D01*
X252138Y-369250D01*
X253666Y-369833D01*
X255194D01*
X256723Y-369250D01*
X258033Y-368375D01*
X259125Y-367209D01*
G01X272912Y-360500D02*
X273786Y-359625D01*
X274441Y-358167D01*
X274878Y-356124D01*
X274441Y-354375D01*
X273568Y-353208D01*
X272039Y-352333D01*
X266144D01*
Y-369833D01*
X273349D01*
X274878Y-368667D01*
X275751Y-366916D01*
X276188Y-364875D01*
X275751Y-362833D01*
X274441Y-361083D01*
X272912Y-360500D01*
X266144D01*
G01X282116Y-375666D02*
X295216D01*
G01X301144Y-369833D02*
Y-352333D01*
X311188Y-369833D01*
Y-352333D01*
G01X323666Y-369833D02*
X321919Y-369541D01*
X320391Y-368375D01*
X319081Y-366625D01*
X318207Y-364583D01*
X317771Y-362250D01*
Y-359916D01*
X318207Y-357583D01*
X319081Y-355541D01*
X320391Y-353792D01*
X321919Y-352625D01*
X323666Y-352333D01*
X325412Y-352625D01*
X326941Y-353792D01*
X328251Y-355541D01*
X329125Y-357583D01*
X329561Y-359916D01*
Y-362250D01*
X329125Y-364583D01*
X328251Y-366625D01*
X326941Y-368375D01*
X325412Y-369541D01*
X323666Y-369833D01*
G01X374507Y-352333D02*
X379966Y-369833D01*
X385425Y-352333D01*
G01X401833Y-369833D02*
X393099D01*
Y-352333D01*
X401833D01*
G01X398339Y-360791D02*
X393099D01*
G01X410599Y-369833D02*
Y-352333D01*
X416058D01*
X417804Y-353208D01*
X418896Y-354375D01*
X419333Y-356708D01*
X418896Y-359042D01*
X417586Y-360500D01*
X416058Y-361375D01*
X410599D01*
G01X416058D02*
X419333Y-369833D01*
G01X432466Y-370416D02*
X432029Y-370125D01*
Y-369541D01*
X432466Y-369250D01*
X432903Y-369541D01*
Y-370125D01*
X432466Y-370416D01*
G01X392881Y-412500D02*
X394628Y-413958D01*
X396593Y-414833D01*
X398339D01*
X400086Y-413958D01*
X401396Y-412500D01*
X402051Y-410458D01*
X401614Y-408417D01*
X400523Y-406666D01*
X398558Y-405500D01*
X395938Y-404916D01*
X394409Y-403750D01*
X393754Y-401708D01*
X394191Y-399666D01*
X395283Y-398208D01*
X396811Y-397333D01*
X398339D01*
X399868Y-397916D01*
X401178Y-399375D01*
G01X410163Y-414833D02*
Y-397333D01*
X414529D01*
X416276Y-398208D01*
X417586Y-399375D01*
X418678Y-401124D01*
X419551Y-403167D01*
X419769Y-406083D01*
X419551Y-409000D01*
X418678Y-411042D01*
X417586Y-412792D01*
X416276Y-413958D01*
X414529Y-414833D01*
X410163D01*
G01X512416Y-397333D02*
Y-414833D01*
G01X507394Y-397333D02*
X517438D01*
G01X524239Y-414833D02*
Y-397333D01*
X529916Y-411916D01*
X535593Y-397333D01*
Y-414833D01*
G01X541957D02*
X547416Y-397333D01*
X552875Y-414833D01*
G01X550909Y-408708D02*
X543922D01*
G01X560331Y-412500D02*
X562078Y-413958D01*
X564043Y-414833D01*
X565789D01*
X567536Y-413958D01*
X568846Y-412500D01*
X569501Y-410458D01*
X569064Y-408417D01*
X567973Y-406666D01*
X566008Y-405500D01*
X563388Y-404916D01*
X561859Y-403750D01*
X561204Y-401708D01*
X561641Y-399666D01*
X562733Y-398208D01*
X564261Y-397333D01*
X565789D01*
X567318Y-397916D01*
X568628Y-399375D01*
G01X577613Y-414833D02*
Y-397333D01*
G01X585909D02*
X577613Y-408125D01*
G01X587219Y-414833D02*
X581324Y-403167D01*
G01X508049Y-352333D02*
Y-369833D01*
X516783D01*
G01X533846D02*
Y-358167D01*
G01Y-360208D02*
X532973Y-359042D01*
X531662Y-358458D01*
X530134Y-358167D01*
X528606Y-358750D01*
X527296Y-359916D01*
X526422Y-361666D01*
X525986Y-364000D01*
X526422Y-366333D01*
X527296Y-368083D01*
X528606Y-369250D01*
X530134Y-369833D01*
X531662Y-369541D01*
X532973Y-368667D01*
X533846Y-367500D01*
G01X542831Y-375083D02*
X544141Y-375666D01*
X545888Y-375083D01*
X546979Y-373917D01*
X547853Y-372458D01*
X549162Y-367792D01*
X552001Y-358167D01*
G01X545014D02*
X549162Y-367792D01*
G01X561641Y-361958D02*
X568628D01*
X567973Y-359916D01*
X566881Y-358750D01*
X565353Y-358167D01*
X563824Y-358458D01*
X562514Y-359333D01*
X561641Y-361375D01*
X561204Y-363125D01*
Y-364875D01*
X561641Y-366625D01*
X562733Y-368375D01*
X564043Y-369541D01*
X565571Y-369833D01*
X567099Y-369250D01*
X568628Y-367500D01*
G01X579359Y-369833D02*
Y-358167D01*
G01Y-360500D02*
X580451Y-359333D01*
X581543Y-358458D01*
X583071Y-358167D01*
X584162Y-358458D01*
X585473Y-359333D01*
G01X672466Y-414833D02*
X670719Y-414541D01*
X669191Y-413375D01*
X667881Y-411625D01*
X667007Y-409583D01*
X666571Y-407250D01*
Y-404916D01*
X667007Y-402583D01*
X667881Y-400541D01*
X669191Y-398792D01*
X670719Y-397625D01*
X672466Y-397333D01*
X674212Y-397625D01*
X675741Y-398792D01*
X677051Y-400541D01*
X677925Y-402583D01*
X678361Y-404916D01*
Y-407250D01*
X677925Y-409583D01*
X677051Y-411625D01*
X675741Y-413375D01*
X674212Y-414541D01*
X672466Y-414833D01*
G01X674212Y-410166D02*
X676833Y-414833D01*
G01X685163Y-397333D02*
Y-409875D01*
X686036Y-412500D01*
X687783Y-414250D01*
X689966Y-414833D01*
X692149Y-414250D01*
X693896Y-412500D01*
X694769Y-409875D01*
Y-397333D01*
G01X704846D02*
X710086D01*
G01X707466D02*
Y-414833D01*
G01X704846D02*
X710086D01*
G01X719944D02*
Y-397333D01*
X729988Y-414833D01*
Y-397333D01*
G01X747269Y-398792D02*
X745959Y-397916D01*
X744431Y-397333D01*
X742684D01*
X740719Y-398208D01*
X739191Y-399666D01*
X738099Y-401417D01*
X737226Y-404333D01*
X737007Y-406958D01*
X737444Y-409583D01*
X738099Y-411333D01*
X739409Y-413083D01*
X740938Y-414250D01*
X742466Y-414833D01*
X743994D01*
X745523Y-414250D01*
X746833Y-413375D01*
X747925Y-412209D01*
G01X759966Y-414833D02*
Y-406958D01*
X755599Y-397333D01*
G01X764333D02*
X759966Y-406958D01*
G01X650163Y-369833D02*
Y-352333D01*
X654529D01*
X656276Y-353208D01*
X657586Y-354375D01*
X658678Y-356124D01*
X659551Y-358167D01*
X659769Y-361083D01*
X659551Y-364000D01*
X658678Y-366042D01*
X657586Y-367792D01*
X656276Y-368958D01*
X654529Y-369833D01*
X650163D01*
G01X669191Y-361958D02*
X676178D01*
X675523Y-359916D01*
X674431Y-358750D01*
X672903Y-358167D01*
X671374Y-358458D01*
X670064Y-359333D01*
X669191Y-361375D01*
X668754Y-363125D01*
Y-364875D01*
X669191Y-366625D01*
X670283Y-368375D01*
X671593Y-369541D01*
X673121Y-369833D01*
X674649Y-369250D01*
X676178Y-367500D01*
G01X686691Y-367792D02*
X687783Y-368958D01*
X689311Y-369833D01*
X690621D01*
X691931Y-369250D01*
X692804Y-368375D01*
X693241Y-367209D01*
X693023Y-365458D01*
X692149Y-364583D01*
X688219Y-362833D01*
X687346Y-360791D01*
X687783Y-359333D01*
X688656Y-358458D01*
X689966Y-358167D01*
X691276Y-358458D01*
X692586Y-359333D01*
G01X707466Y-358167D02*
Y-369833D01*
G01Y-353500D02*
X707029Y-353208D01*
Y-352625D01*
X707466Y-352333D01*
X707903Y-352625D01*
Y-353208D01*
X707466Y-353500D01*
G01X721909Y-374208D02*
X723438Y-375375D01*
X725184Y-375666D01*
X726712Y-375375D01*
X728023Y-373917D01*
X728896Y-371875D01*
Y-358167D01*
G01Y-360500D02*
X728023Y-359333D01*
X726712Y-358458D01*
X725184Y-358167D01*
X723438Y-358750D01*
X722346Y-359916D01*
X721472Y-361958D01*
X721036Y-364000D01*
X721254Y-365750D01*
X722128Y-367792D01*
X723438Y-369250D01*
X725184Y-369833D01*
X726494Y-369541D01*
X728023Y-368375D01*
X728896Y-367209D01*
G01X738754Y-369833D02*
Y-358167D01*
G01Y-361083D02*
X739628Y-359625D01*
X740938Y-358458D01*
X742684Y-358167D01*
X744212Y-358458D01*
X745523Y-359625D01*
X746178Y-361666D01*
Y-369833D01*
G01X756691Y-361958D02*
X763678D01*
X763023Y-359916D01*
X761931Y-358750D01*
X760403Y-358167D01*
X758874Y-358458D01*
X757564Y-359333D01*
X756691Y-361375D01*
X756254Y-363125D01*
Y-364875D01*
X756691Y-366625D01*
X757783Y-368375D01*
X759093Y-369541D01*
X760621Y-369833D01*
X762149Y-369250D01*
X763678Y-367500D01*
G01X774409Y-369833D02*
Y-358167D01*
G01Y-360500D02*
X775501Y-359333D01*
X776593Y-358458D01*
X778121Y-358167D01*
X779212Y-358458D01*
X780523Y-359333D01*
G01X821166Y-397333D02*
X819419Y-397916D01*
X818109Y-399375D01*
X817236Y-401124D01*
X816581Y-403458D01*
X816363Y-406083D01*
X816581Y-408708D01*
X817236Y-411042D01*
X818109Y-412792D01*
X819419Y-414250D01*
X821166Y-414833D01*
X822912Y-414250D01*
X824223Y-412792D01*
X825096Y-411042D01*
X825751Y-408708D01*
X825969Y-406083D01*
X825751Y-403458D01*
X825096Y-401124D01*
X824223Y-399375D01*
X822912Y-397916D01*
X821166Y-397333D01*
G01X833863Y-411333D02*
X835172Y-413375D01*
X836919Y-414541D01*
X838884Y-414833D01*
X840631Y-414541D01*
X842378Y-413083D01*
X843469Y-411333D01*
X843688Y-409583D01*
X843251Y-407542D01*
X841723Y-406083D01*
X840194Y-405500D01*
X838229D01*
G01X840194D02*
X841504Y-404625D01*
X842596Y-403167D01*
X843033Y-401417D01*
X842596Y-399666D01*
X841504Y-398208D01*
X839539Y-397333D01*
X837574Y-397625D01*
X835609Y-398792D01*
G01X852236Y-415416D02*
X860096Y-397333D01*
G01X869518Y-400250D02*
X870828Y-398500D01*
X872356Y-397625D01*
X874103Y-397333D01*
X876286Y-397916D01*
X877814Y-399375D01*
X878251Y-401124D01*
X878033Y-402875D01*
X877159Y-404333D01*
X872793Y-407250D01*
X870828Y-409291D01*
X869518Y-412209D01*
X869081Y-414833D01*
X878251D01*
G01X887454Y-412792D02*
X888983Y-414250D01*
X890729Y-414833D01*
X892476Y-414250D01*
X894004Y-412500D01*
X895096Y-409875D01*
X895533Y-407250D01*
Y-404042D01*
X895096Y-401417D01*
X894004Y-399083D01*
X892694Y-397916D01*
X891166Y-397333D01*
X889419Y-397916D01*
X888109Y-399083D01*
X887236Y-400833D01*
X886799Y-403167D01*
X887236Y-405208D01*
X888328Y-407250D01*
X889638Y-408417D01*
X891166Y-408708D01*
X892912Y-408125D01*
X894223Y-406666D01*
X895533Y-404042D01*
G01X904736Y-415416D02*
X912596Y-397333D01*
G01X922018Y-400250D02*
X923328Y-398500D01*
X924856Y-397625D01*
X926603Y-397333D01*
X928786Y-397916D01*
X930314Y-399375D01*
X930751Y-401124D01*
X930533Y-402875D01*
X929659Y-404333D01*
X925293Y-407250D01*
X923328Y-409291D01*
X922018Y-412209D01*
X921581Y-414833D01*
X930751D01*
G01X943666Y-397333D02*
X941919Y-397916D01*
X940609Y-399375D01*
X939736Y-401124D01*
X939081Y-403458D01*
X938863Y-406083D01*
X939081Y-408708D01*
X939736Y-411042D01*
X940609Y-412792D01*
X941919Y-414250D01*
X943666Y-414833D01*
X945412Y-414250D01*
X946723Y-412792D01*
X947596Y-411042D01*
X948251Y-408708D01*
X948469Y-406083D01*
X948251Y-403458D01*
X947596Y-401124D01*
X946723Y-399375D01*
X945412Y-397916D01*
X943666Y-397333D01*
G01X961166Y-414833D02*
Y-397333D01*
X958546Y-400833D01*
G01Y-414833D02*
X963786D01*
G01X978229D02*
X978666Y-411042D01*
X979321Y-407833D01*
X980194Y-404916D01*
X981286Y-401708D01*
X983033Y-397333D01*
X974299D01*
G01X868863Y-369833D02*
Y-352333D01*
X873229D01*
X874976Y-353208D01*
X876286Y-354375D01*
X877378Y-356124D01*
X878251Y-358167D01*
X878469Y-361083D01*
X878251Y-364000D01*
X877378Y-366042D01*
X876286Y-367792D01*
X874976Y-368958D01*
X873229Y-369833D01*
X868863D01*
G01X895096D02*
Y-358167D01*
G01Y-360208D02*
X894223Y-359042D01*
X892912Y-358458D01*
X891384Y-358167D01*
X889856Y-358750D01*
X888546Y-359916D01*
X887672Y-361666D01*
X887236Y-364000D01*
X887672Y-366333D01*
X888546Y-368083D01*
X889856Y-369250D01*
X891384Y-369833D01*
X892912Y-369541D01*
X894223Y-368667D01*
X895096Y-367500D01*
G01X908666Y-352333D02*
Y-369833D01*
G01X905609Y-358167D02*
X911723D01*
G01X922891Y-361958D02*
X929878D01*
X929223Y-359916D01*
X928131Y-358750D01*
X926603Y-358167D01*
X925074Y-358458D01*
X923764Y-359333D01*
X922891Y-361375D01*
X922454Y-363125D01*
Y-364875D01*
X922891Y-366625D01*
X923983Y-368375D01*
X925293Y-369541D01*
X926821Y-369833D01*
X928349Y-369250D01*
X929878Y-367500D01*
G54D56*
X116339Y78740D03*
G54D38*
X47933Y128937D03*
X16633D03*
X47933Y146653D03*
X16633D03*
X208170Y128937D03*
X176870D03*
X208170Y146653D03*
X176870D03*
G54D29*
X31500Y112222D03*
Y110252D03*
Y108282D03*
X29058D03*
Y110252D03*
Y112222D03*
X209976Y119370D03*
Y117400D03*
Y115430D03*
X207534D03*
Y117400D03*
Y119370D03*
G54D47*
X22398Y154767D03*
G54D39*
X16538Y173177D03*
X12600D03*
X16538Y167477D03*
X14569D03*
X12600D03*
X217790Y221230D03*
X215821D03*
X213852D03*
X217790Y226930D03*
X213852D03*
G54D57*
X191900Y115700D03*
X185900D03*
G54D48*
X16798Y154767D03*
G54D49*
X7985Y222487D03*
G54D58*
X215520Y140700D03*
G54D59*
Y146300D03*
M02*
